# BASEBOARD_FAB2 (Tioga Pass) — schematic netlist excerpt (pin names and nets, part order shuffled) for the footprints in the layout excerpt that follows; sources: Cadence DE-HDL packaged netlist, KiCad conversion of Wiwynn_Tioga_Pass_MB.brd

C5G82  CAP_A  22.0UF 4V 20% X6S  pkg 0603V  page 243 : A = PVDDQ_GHJ ; B = GND

T1D5  TEST-PAD-12P-1-GP-U  pkg DISCRET-GB1  page 257
  DP  = L5_85OHM_5INCH_DP
  DN  = L5_85OHM_5INCH_DN
  GND(0)  = GND
  GND(1)  = GND
  GND(2)  = GND
  GND(3)  = GND
  GND(4)  = GND
  GND(5)  = GND
  GND(6)  = GND
  GND(7)  = GND
  GND(8)  = GND
  GND(9)  = GND

(kicad_pcb
	(version 20260206)
	(generator "pcbnew")
	(generator_version "10.0")
	(general
		(thickness 1.6)
		(legacy_teardrops no)
	)
	(paper "A4")
	(title_block
		(title "Wiwynn_Tioga_Pass_MB.brd")
		(comment 1 "Tioga Pass / footprints 3329-3330 of 4770")
	)
	(layers
		(0 "F.Cu" signal "TOP")
		(4 "In1.Cu" signal "L2GND")
		(6 "In2.Cu" signal "L3")
		(8 "In3.Cu" signal "L4GND")
		(10 "In4.Cu" signal "L5")
		(12 "In5.Cu" signal "L6GND")
		(14 "In6.Cu" signal "L7VCC")
		(16 "In7.Cu" signal "L8VCC")
		(18 "In8.Cu" signal "L9GND")
		(20 "In9.Cu" signal "L10")
		(22 "In10.Cu" signal "L11GND")
		(24 "In11.Cu" signal "L12")
		(26 "In12.Cu" signal "L13GND")
		(2 "B.Cu" signal "BOTTOM")
		(9 "F.Adhes" user "F.Adhesive")
		(11 "B.Adhes" user "B.Adhesive")
		(13 "F.Paste" user "Package Geometry/Pastemask Top")
		(15 "B.Paste" user "Package Geometry/Pastemask Bottom")
		(5 "F.SilkS" user "Ref Des/Silkscreen Top")
		(7 "B.SilkS" user "Ref Des/Silkscreen Bottom")
		(1 "F.Mask" user "Board Geometry/Soldermask Top")
		(3 "B.Mask" user "Board Geometry/Soldermask Bottom")
		(17 "Dwgs.User" user "User.Drawings")
		(19 "Cmts.User" user "User.Comments")
		(21 "Eco1.User" user "User.Eco1")
		(23 "Eco2.User" user "User.Eco2")
		(25 "Edge.Cuts" user "Board Geometry/Outline")
		(27 "Margin" user)
		(31 "F.CrtYd" user "Package Geometry/Place Bound Top")
		(29 "B.CrtYd" user "Package Geometry/Place Bound Bottom")
		(35 "F.Fab" user "Ref Des/Assembly Top")
		(33 "B.Fab" user "Ref Des/Assembly Bottom")
	)
	(footprint ""
		(layer "B.Cu")
		(at 108.9025 -164.973 -90)
		(property "Reference" "T1D5"
			(at 0 0 90)
			(layer "B.SilkS")
			(hide yes)
			(effects
				(font
					(size 1.27 1.27)
				)
				(justify mirror)
			)
		)
		(property "Value" "*"
			(at 3.4036 -4.46405 270)
			(unlocked yes)
			(layer "B.Fab")
			(hide yes)
			(effects
				(font
					(size 0.889 0.889)
					(thickness 0.1524)
				)
				(justify mirror)
			)
		)
		(property "Device Type" "TEST-PAD-12P-1-GP-U_DISCRET-GBA"
			(at 3.4036 -5.98805 270)
			(unlocked yes)
			(layer "B.Fab")
			(hide yes)
			(effects
				(font
					(size 0.889 0.889)
					(thickness 0.1524)
				)
				(justify mirror)
			)
		)
		(duplicate_pad_numbers_are_jumpers no)
		(fp_line
			(start -2.3622 3.4798)
			(end 2.3876 3.4798)
			(stroke
				(width 0.1524)
				(type default)
			)
			(layer "B.SilkS")
		)
		(fp_line
			(start 2.3876 3.4798)
			(end 2.3876 -4.826)
			(stroke
				(width 0.1524)
				(type default)
			)
			(layer "B.SilkS")
		)
		(fp_line
			(start -2.3622 -4.826)
			(end -2.3622 3.4798)
			(stroke
				(width 0.1524)
				(type default)
			)
			(layer "B.SilkS")
		)
		(fp_line
			(start 2.3876 -4.826)
			(end -2.3622 -4.826)
			(stroke
				(width 0.1524)
				(type default)
			)
			(layer "B.SilkS")
		)
		(fp_rect
			(start 2.6416 3.7338)
			(end -2.6162 -5.08)
			(stroke
				(width 0)
				(type default)
			)
			(fill no)
			(layer "B.CrtYd")
		)
		(fp_rect
			(start 2.6416 3.7338)
			(end -2.6162 -5.08)
			(stroke
				(width 0)
				(type default)
			)
			(fill no)
			(layer "B.Fab")
		)
		(pad "1" smd circle
			(at -0.496824 -1.301496 90)
			(size 0.6604 0.6604)
			(layers "B.Cu" "B.Mask" "B.Paste")
			(net "L5_85OHM_5INCH_DP")
		)
		(pad "2" smd circle
			(at 0.503936 -1.301496 90)
			(size 0.6604 0.6604)
			(layers "B.Cu" "B.Mask" "B.Paste")
			(net "L5_85OHM_5INCH_DN")
		)
		(pad "3" smd custom
			(at 0.00889 0.370078 90)
			(size 0.74295 0.74295)
			(layers "B.Cu" "B.Mask" "B.Paste")
			(net "GND")
			(options
				(clearance outline)
				(anchor circle)
			)
			(primitives
				(gr_poly
					(pts
						(xy -2.1209 -1.4859) (xy 2.1209 -1.4859) (xy 2.1209 1.4859) (xy 1.08585 1.4859) (xy 1.08585 0.4699)
						(xy -1.08585 0.4699) (xy -1.08585 1.4859) (xy -2.1209 1.4859)
					)
					(width 0)
					(fill yes)
				)
			)
		)
		(pad "4" thru_hole circle
			(at -1.266444 -3.851656 90)
			(size 1.4478 1.4478)
			(drill 1.0414)
			(layers "*.Cu" "*.Mask")
			(remove_unused_layers no)
			(net "GND")
			(clearance 0.1524)
			(thermal_gap 0.1524)
		)
		(pad "5" thru_hole circle
			(at 1.273556 -3.851656 90)
			(size 1.4478 1.4478)
			(drill 1.0414)
			(layers "*.Cu" "*.Mask")
			(remove_unused_layers no)
			(net "GND")
			(clearance 0.1524)
			(thermal_gap 0.1524)
		)
		(pad "6" thru_hole circle
			(at -1.266444 2.498344 90)
			(size 1.4478 1.4478)
			(drill 1.0414)
			(layers "*.Cu" "*.Mask")
			(remove_unused_layers no)
			(net "GND")
			(clearance 0.1524)
			(thermal_gap 0.1524)
		)
		(pad "7" thru_hole circle
			(at 1.273556 2.498344 90)
			(size 1.4478 1.4478)
			(drill 1.0414)
			(layers "*.Cu" "*.Mask")
			(remove_unused_layers no)
			(net "GND")
			(clearance 0.1524)
			(thermal_gap 0.1524)
		)
		(pad "8" thru_hole circle
			(at -1.27 -0.4572 90)
			(size 0.7112 0.7112)
			(drill 0.4064)
			(layers "*.Cu" "*.Mask")
			(remove_unused_layers no)
			(net "GND")
			(clearance 0.1016)
			(thermal_gap 0.1016)
		)
		(pad "9" thru_hole circle
			(at -1.27 0.762 90)
			(size 0.7112 0.7112)
			(drill 0.4064)
			(layers "*.Cu" "*.Mask")
			(remove_unused_layers no)
			(net "GND")
			(clearance 0.1016)
			(thermal_gap 0.1016)
		)
		(pad "10" thru_hole circle
			(at 0.0254 0.762 90)
			(size 0.7112 0.7112)
			(drill 0.4064)
			(layers "*.Cu" "*.Mask")
			(remove_unused_layers no)
			(net "GND")
			(clearance 0.1016)
			(thermal_gap 0.1016)
		)
		(pad "11" thru_hole circle
			(at 1.27 0.762 90)
			(size 0.7112 0.7112)
			(drill 0.4064)
			(layers "*.Cu" "*.Mask")
			(remove_unused_layers no)
			(net "GND")
			(clearance 0.1016)
			(thermal_gap 0.1016)
		)
		(pad "12" thru_hole circle
			(at 1.27 -0.4572 90)
			(size 0.7112 0.7112)
			(drill 0.4064)
			(layers "*.Cu" "*.Mask")
			(remove_unused_layers no)
			(net "GND")
			(clearance 0.1016)
			(thermal_gap 0.1016)
		)
	)
	(footprint ""
		(layer "B.Cu")
		(at 88.392 -12.954 90)
		(property "Reference" "C5G82"
			(at -1.14681 0.76708 180)
			(unlocked yes)
			(layer "B.SilkS")
			(effects
				(font
					(size 0.7874 0.5842)
					(thickness 0.1524)
				)
				(justify mirror)
			)
		)
		(property "Value" ""
			(at 0 0 90)
			(layer "B.Fab")
			(effects
				(font
					(size 1.27 1.27)
				)
				(justify mirror)
			)
		)
		(duplicate_pad_numbers_are_jumpers no)
		(fp_rect
			(start -0.4953 -0.2032)
			(end 0.4953 1.6002)
			(stroke
				(width 0)
				(type default)
			)
			(fill no)
			(layer "B.CrtYd")
		)
		(fp_line
			(start 0.4953 -0.2032)
			(end -0.4953 -0.2032)
			(stroke
				(width 0.1)
				(type default)
			)
			(layer "B.Fab")
		)
		(fp_line
			(start -0.4953 -0.2032)
			(end -0.4953 1.6002)
			(stroke
				(width 0.1)
				(type default)
			)
			(layer "B.Fab")
		)
		(fp_line
			(start 0.4953 1.6002)
			(end 0.4953 -0.2032)
			(stroke
				(width 0.1)
				(type default)
			)
			(layer "B.Fab")
		)
		(fp_line
			(start -0.4953 1.6002)
			(end 0.4953 1.6002)
			(stroke
				(width 0.1)
				(type default)
			)
			(layer "B.Fab")
		)
		(pad "1" smd rect
			(at 0 0 270)
			(size 0.762 0.889)
			(layers "B.Cu" "B.Mask" "B.Paste")
			(net "PVDDQ_GHJ")
		)
		(pad "2" smd rect
			(at 0 1.397 270)
			(size 0.762 0.889)
			(layers "B.Cu" "B.Mask" "B.Paste")
			(net "GND")
		)
		(zone
			(layer "B.Cu")
			(hatch none 0.5)
			(connect_pads
				(clearance 0)
			)
			(min_thickness 0.25)
			(keepout
				(tracks not_allowed)
				(vias allowed)
				(pads allowed)
				(copperpour not_allowed)
				(footprints allowed)
			)
			(placement
				(enabled no)
				(sheetname "")
			)
			(fill
				(thermal_gap 0.5)
				(thermal_bridge_width 0.5)
				(island_removal_mode 0)
			)
			(polygon
				(pts
					(xy 88.8365 -12.573) (xy 89.3445 -12.573) (xy 89.3445 -13.335) (xy 88.8365 -13.335)
				)
			)
		)
	)
)
